FILE_TYPE = MULTI_PHYS_TABLE;

PART 'RT9059GQW'

{========================================================================================}
:VALUE       | PART_TYPE | MATERIAL | PART_NUMBER      = STANDARD | LIFECYCLE     | PART_NUMBER   | JEDEC_TYPE   | DESCRIPTION                     | MANUFTR | MANUF_PN    | RD_CMPLS_LVL | CMPLS_LVL | FROM_PJ    | CLASS | DIP_SMD | DATA                     | EE_CHECK_LIST | FP_ECN | PSL | CREATOR | STATUS | CREATEDAY  ;
{========================================================================================}
 'RT9059GQW' | 'SMLF'    | 'IC'     | 'AL009059000'(!) = ''       | ''               | 'AL009059000' |'DFN10_THXE'| 'IC OTHER(10P) RT9059GQW(WDFN)' | 'RTK'   | 'RT9059GQW' | 'EP(V1)'     | ''        | 'S4E-ALAN' | 'IC'  | ''      | 'RTK_RT9059_rev2012.pdf' | ''            | ''     | ''  | ''      | ''     | '20120514'
 'RT9059GQW' | 'SMLF'    | 'EMPTY'  | 'AL009059000'(!) = ''       | ''               | 'AL009059000' |'DFN10_THXE'| 'IC OTHER(10P) RT9059GQW(WDFN)' | 'RTK'   | 'RT9059GQW' | 'EP(V1)'     | ''        | 'S4E-ALAN' | 'IC'  | ''      | 'RTK_RT9059_rev2012.pdf' | ''            | ''     | ''  | ''      | ''     | '20120514'

END_PART

END.

